# T6G (Grand Teton) — schematic netlist excerpt (pin names and nets, part order shuffled) for the footprints in the layout excerpt that follows; sources: Cadence DE-HDL packaged netlist, KiCad conversion of 04192023_DAF0TMB3IC0_F0TG_MB_C_brd_V02_OCP.brd

PR356  Q_RES  2.2 1% CHIP  pkg 0402LF  page 198 : A = PVDDCR_CPU0_P0_PVCC ; B = PVDDCR_SOC_P0_VCC1

DB16  TDR_3P  EMPTY  pkg TH2  page 260
  GND  = T1_GND
  IO1  = TDR_SE_50_OHM_IN6
  IO2  = TDR_SE_50_OHM_IN6

C218  Q_CAP  0.1UF 25V 10% X7R  pkg 0402  page 166 : A = P1V8_AUX ; B = GND

(kicad_pcb
	(version 20260206)
	(generator "pcbnew")
	(generator_version "10.0")
	(general
		(thickness 1.6)
		(legacy_teardrops no)
	)
	(paper "A4")
	(title_block
		(title "04192023_DAF0TMB3IC0_F0TG_MB_C_brd_V02_OCP.brd")
		(comment 1 "Grand Teton / footprints 7315-7317 of 8354")
	)
	(layers
		(0 "F.Cu" signal "TOP")
		(4 "In1.Cu" signal "GND")
		(6 "In2.Cu" signal "IN1")
		(8 "In3.Cu" signal "GND1")
		(10 "In4.Cu" signal "IN2")
		(12 "In5.Cu" signal "GND2")
		(14 "In6.Cu" signal "IN3")
		(16 "In7.Cu" signal "GND3")
		(18 "In8.Cu" signal "VCC")
		(20 "In9.Cu" signal "VCC1")
		(22 "In10.Cu" signal "GND4")
		(24 "In11.Cu" signal "IN4")
		(26 "In12.Cu" signal "GND5")
		(28 "In13.Cu" signal "IN5")
		(30 "In14.Cu" signal "GND6")
		(32 "In15.Cu" signal "IN6")
		(34 "In16.Cu" signal "GND7")
		(2 "B.Cu" signal "BOTTOM")
		(9 "F.Adhes" user "F.Adhesive")
		(11 "B.Adhes" user "B.Adhesive")
		(13 "F.Paste" user "Package Geometry/Pastemask Top")
		(15 "B.Paste" user "Package Geometry/Pastemask Bottom")
		(5 "F.SilkS" user "Ref Des/Silkscreen Top")
		(7 "B.SilkS" user "Ref Des/Silkscreen Bottom")
		(1 "F.Mask" user "Board Geometry/Soldermask Top")
		(3 "B.Mask" user "Board Geometry/Soldermask Bottom")
		(17 "Dwgs.User" user "User.Drawings")
		(19 "Cmts.User" user "User.Comments")
		(21 "Eco1.User" user "User.Eco1")
		(23 "Eco2.User" user "User.Eco2")
		(25 "Edge.Cuts" user "Board Geometry/Outline")
		(27 "Margin" user)
		(31 "F.CrtYd" user "Package Geometry/Place Bound Top")
		(29 "B.CrtYd" user "Package Geometry/Place Bound Bottom")
		(35 "F.Fab" user "Ref Des/Assembly Top")
		(33 "B.Fab" user "Ref Des/Assembly Bottom")
	)
	(footprint ""
		(layer "B.Cu")
		(at 401.554696 -341.172292 90)
		(property "Reference" "C218"
			(at 0 0 90)
			(layer "B.SilkS")
			(hide yes)
			(effects
				(font
					(size 1.27 1.27)
				)
				(justify mirror)
			)
		)
		(property "Value" ""
			(at 0 0 90)
			(layer "B.Fab")
			(effects
				(font
					(size 1.27 1.27)
				)
				(justify mirror)
			)
		)
		(duplicate_pad_numbers_are_jumpers no)
		(fp_line
			(start 0.7874 -0.4064)
			(end -0.7874 -0.4064)
			(stroke
				(width 0.1524)
				(type default)
			)
			(layer "B.SilkS")
		)
		(fp_line
			(start -0.7874 -0.4064)
			(end -0.7874 0.4064)
			(stroke
				(width 0.1524)
				(type default)
			)
			(layer "B.SilkS")
		)
		(fp_line
			(start 0.7874 0.4064)
			(end 0.7874 -0.4064)
			(stroke
				(width 0.1524)
				(type default)
			)
			(layer "B.SilkS")
		)
		(fp_line
			(start -0.7874 0.4064)
			(end 0.7874 0.4064)
			(stroke
				(width 0.1524)
				(type default)
			)
			(layer "B.SilkS")
		)
		(fp_line
			(start 0.67945 -0.305054)
			(end 0.12065 -0.305054)
			(stroke
				(width 0.1)
				(type default)
			)
			(layer "B.Fab")
		)
		(fp_line
			(start 0.12065 -0.305054)
			(end 0.12065 -0.2794)
			(stroke
				(width 0.1)
				(type default)
			)
			(layer "B.Fab")
		)
		(fp_line
			(start -0.12065 -0.3048)
			(end -0.67945 -0.3048)
			(stroke
				(width 0.1)
				(type default)
			)
			(layer "B.Fab")
		)
		(fp_line
			(start -0.67945 -0.3048)
			(end -0.67945 0.3048)
			(stroke
				(width 0.1)
				(type default)
			)
			(layer "B.Fab")
		)
		(fp_line
			(start 0.12065 -0.2794)
			(end -0.12065 -0.2794)
			(stroke
				(width 0.1)
				(type default)
			)
			(layer "B.Fab")
		)
		(fp_line
			(start -0.12065 -0.2794)
			(end -0.12065 -0.3048)
			(stroke
				(width 0.1)
				(type default)
			)
			(layer "B.Fab")
		)
		(fp_line
			(start 0.12065 0.2794)
			(end 0.12065 0.3048)
			(stroke
				(width 0.1)
				(type default)
			)
			(layer "B.Fab")
		)
		(fp_line
			(start -0.120396 0.2794)
			(end 0.12065 0.2794)
			(stroke
				(width 0.1)
				(type default)
			)
			(layer "B.Fab")
		)
		(fp_line
			(start 0.67945 0.3048)
			(end 0.67945 -0.305054)
			(stroke
				(width 0.1)
				(type default)
			)
			(layer "B.Fab")
		)
		(fp_line
			(start 0.12065 0.3048)
			(end 0.67945 0.3048)
			(stroke
				(width 0.1)
				(type default)
			)
			(layer "B.Fab")
		)
		(fp_line
			(start -0.120396 0.3048)
			(end -0.120396 0.2794)
			(stroke
				(width 0.1)
				(type default)
			)
			(layer "B.Fab")
		)
		(fp_line
			(start -0.67945 0.3048)
			(end -0.120396 0.3048)
			(stroke
				(width 0.1)
				(type default)
			)
			(layer "B.Fab")
		)
		(pad "1" smd circle
			(at 0.40005 0 270)
			(size 0 0)
			(layers "B.Cu" "B.Mask" "B.Paste")
			(net "P1V8_AUX")
		)
		(pad "2" smd circle
			(at -0.40005 0 270)
			(size 0 0)
			(layers "B.Cu" "B.Mask" "B.Paste")
			(net "GND")
		)
	)
	(footprint ""
		(layer "B.Cu")
		(at 527.561048 -24.162512)
		(property "Reference" "DB16"
			(at 2.586228 -5.512308 270)
			(unlocked yes)
			(layer "B.SilkS")
			(effects
				(font
					(size 0.7874 0.5842)
					(thickness 0.1524)
				)
				(justify left mirror)
			)
		)
		(property "Value" ""
			(at 0 0 0)
			(layer "B.Fab")
			(effects
				(font
					(size 1.27 1.27)
				)
				(justify mirror)
			)
		)
		(duplicate_pad_numbers_are_jumpers no)
		(fp_line
			(start -3.330702 -4.771136)
			(end 0 4.011168)
			(stroke
				(width 0.1524)
				(type default)
			)
			(layer "B.SilkS")
		)
		(fp_line
			(start 0 4.011168)
			(end 3.330702 -4.771136)
			(stroke
				(width 0.1524)
				(type default)
			)
			(layer "B.SilkS")
		)
		(fp_line
			(start 3.330702 -4.771136)
			(end -3.330702 -4.771136)
			(stroke
				(width 0.1524)
				(type default)
			)
			(layer "B.SilkS")
		)
		(fp_line
			(start -3.330702 -4.771136)
			(end 0 4.011168)
			(stroke
				(width 0.1)
				(type default)
			)
			(layer "B.Fab")
		)
		(fp_line
			(start 0 4.011168)
			(end 3.330702 -4.771136)
			(stroke
				(width 0.1)
				(type default)
			)
			(layer "B.Fab")
		)
		(fp_line
			(start 3.330702 -4.771136)
			(end -3.330702 -4.771136)
			(stroke
				(width 0.1)
				(type default)
			)
			(layer "B.Fab")
		)
		(pad "1" thru_hole circle
			(at 0 0 180)
			(size 2.159 2.159)
			(drill 1.7018)
			(layers "*.Cu" "*.Mask")
			(remove_unused_layers no)
			(net "T1_GND")
			(clearance 0.0254)
			(thermal_gap 0.0254)
		)
		(pad "2" thru_hole circle
			(at 1.27 -3.348736 180)
			(size 2.159 2.159)
			(drill 1.7018)
			(layers "*.Cu" "*.Mask")
			(remove_unused_layers no)
			(net "TDR_SE_50_OHM_IN6")
			(clearance 0.0254)
			(thermal_gap 0.0254)
		)
		(pad "3" thru_hole circle
			(at -1.27 -3.348736 180)
			(size 2.159 2.159)
			(drill 1.7018)
			(layers "*.Cu" "*.Mask")
			(remove_unused_layers no)
			(net "TDR_SE_50_OHM_IN6")
			(clearance 0.0254)
			(thermal_gap 0.0254)
		)
	)
	(footprint ""
		(layer "B.Cu")
		(at 400.13509 -176.111916 90)
		(property "Reference" "PR356"
			(at 0 0 90)
			(layer "B.SilkS")
			(hide yes)
			(effects
				(font
					(size 1.27 1.27)
				)
				(justify mirror)
			)
		)
		(property "Value" ""
			(at 0 0 90)
			(layer "B.Fab")
			(effects
				(font
					(size 1.27 1.27)
				)
				(justify mirror)
			)
		)
		(duplicate_pad_numbers_are_jumpers no)
		(fp_line
			(start 0.7874 -0.4064)
			(end -0.7874 -0.4064)
			(stroke
				(width 0.1524)
				(type default)
			)
			(layer "B.SilkS")
		)
		(fp_line
			(start -0.7874 -0.4064)
			(end -0.7874 0.4064)
			(stroke
				(width 0.1524)
				(type default)
			)
			(layer "B.SilkS")
		)
		(fp_line
			(start 0.7874 0.4064)
			(end 0.7874 -0.4064)
			(stroke
				(width 0.1524)
				(type default)
			)
			(layer "B.SilkS")
		)
		(fp_line
			(start -0.7874 0.4064)
			(end 0.7874 0.4064)
			(stroke
				(width 0.1524)
				(type default)
			)
			(layer "B.SilkS")
		)
		(fp_line
			(start 0.67945 -0.305054)
			(end 0.12065 -0.305054)
			(stroke
				(width 0.1)
				(type default)
			)
			(layer "B.Fab")
		)
		(fp_line
			(start 0.12065 -0.305054)
			(end 0.12065 -0.2794)
			(stroke
				(width 0.1)
				(type default)
			)
			(layer "B.Fab")
		)
		(fp_line
			(start -0.12065 -0.3048)
			(end -0.67945 -0.3048)
			(stroke
				(width 0.1)
				(type default)
			)
			(layer "B.Fab")
		)
		(fp_line
			(start -0.67945 -0.3048)
			(end -0.67945 0.3048)
			(stroke
				(width 0.1)
				(type default)
			)
			(layer "B.Fab")
		)
		(fp_line
			(start 0.12065 -0.2794)
			(end -0.12065 -0.2794)
			(stroke
				(width 0.1)
				(type default)
			)
			(layer "B.Fab")
		)
		(fp_line
			(start -0.12065 -0.2794)
			(end -0.12065 -0.3048)
			(stroke
				(width 0.1)
				(type default)
			)
			(layer "B.Fab")
		)
		(fp_line
			(start 0.12065 0.2794)
			(end 0.12065 0.3048)
			(stroke
				(width 0.1)
				(type default)
			)
			(layer "B.Fab")
		)
		(fp_line
			(start -0.120396 0.2794)
			(end 0.12065 0.2794)
			(stroke
				(width 0.1)
				(type default)
			)
			(layer "B.Fab")
		)
		(fp_line
			(start 0.67945 0.3048)
			(end 0.67945 -0.305054)
			(stroke
				(width 0.1)
				(type default)
			)
			(layer "B.Fab")
		)
		(fp_line
			(start 0.12065 0.3048)
			(end 0.67945 0.3048)
			(stroke
				(width 0.1)
				(type default)
			)
			(layer "B.Fab")
		)
		(fp_line
			(start -0.120396 0.3048)
			(end -0.120396 0.2794)
			(stroke
				(width 0.1)
				(type default)
			)
			(layer "B.Fab")
		)
		(fp_line
			(start -0.67945 0.3048)
			(end -0.120396 0.3048)
			(stroke
				(width 0.1)
				(type default)
			)
			(layer "B.Fab")
		)
		(pad "1" smd circle
			(at 0.40005 0 270)
			(size 0 0)
			(layers "B.Cu" "B.Mask" "B.Paste")
			(net "PVDDCR_CPU0_P0_PVCC")
		)
		(pad "2" smd circle
			(at -0.40005 0 270)
			(size 0 0)
			(layers "B.Cu" "B.Mask" "B.Paste")
			(net "PVDDCR_SOC_P0_VCC1")
		)
	)
)
